(kicad_pcb
	(version 20260206)
	(generator "pcbnew")
	(generator_version "10.0")
	(general
		(thickness 1.6)
		(legacy_teardrops no)
	)
	(paper "A4")
	(title_block
		(title "Bryce Canyon_F.DPB_16315-1-OCP.brd")
		(comment 1 "Bryce Canyon / footprints 2060-2068 of 2223")
	)
	(layers
		(0 "F.Cu" signal "TOP")
		(4 "In1.Cu" signal "L2GND")
		(6 "In2.Cu" signal "L3")
		(8 "In3.Cu" signal "L4GND")
		(10 "In4.Cu" signal "L5")
		(12 "In5.Cu" signal "L6VCC")
		(14 "In6.Cu" signal "L7VCC")
		(16 "In7.Cu" signal "L8")
		(18 "In8.Cu" signal "L9GND")
		(20 "In9.Cu" signal "L10")
		(22 "In10.Cu" signal "L11GND")
		(2 "B.Cu" signal "BOTTOM")
		(9 "F.Adhes" user "F.Adhesive")
		(11 "B.Adhes" user "B.Adhesive")
		(13 "F.Paste" user "Package Geometry/Pastemask Top")
		(15 "B.Paste" user "Package Geometry/Pastemask Bottom")
		(5 "F.SilkS" user "Ref Des/Silkscreen Top")
		(7 "B.SilkS" user "Ref Des/Silkscreen Bottom")
		(1 "F.Mask" user "Board Geometry/Soldermask Top")
		(3 "B.Mask" user "Board Geometry/Soldermask Bottom")
		(17 "Dwgs.User" user "User.Drawings")
		(19 "Cmts.User" user "User.Comments")
		(21 "Eco1.User" user "User.Eco1")
		(23 "Eco2.User" user "User.Eco2")
		(25 "Edge.Cuts" user "Board Geometry/Outline")
		(27 "Margin" user)
		(31 "F.CrtYd" user "Package Geometry/Place Bound Top")
		(29 "B.CrtYd" user "Package Geometry/Place Bound Bottom")
		(35 "F.Fab" user "Ref Des/Assembly Top")
		(33 "B.Fab" user "Ref Des/Assembly Bottom")
	)
	(footprint ""
		(layer "B.Cu")
		(at 364.7948 -142.2654)
		(property "Reference" "C559"
			(at 0 0 0)
			(layer "B.SilkS")
			(hide yes)
			(effects
				(font
					(size 1.27 1.27)
				)
				(justify mirror)
			)
		)
		(property "Value" "SCD015U25V2KX-GP"
			(at -1.1811 -2.7051 0)
			(unlocked yes)
			(layer "B.Fab")
			(hide yes)
			(effects
				(font
					(size 1.016 1.016)
					(thickness 0.1524)
				)
				(justify mirror)
			)
		)
		(property "Device Type" "C402H22"
			(at -1.1811 -4.2291 0)
			(unlocked yes)
			(layer "B.Fab")
			(hide yes)
			(effects
				(font
					(size 1.016 1.016)
					(thickness 0.1524)
				)
				(justify mirror)
			)
		)
		(duplicate_pad_numbers_are_jumpers no)
		(fp_rect
			(start 0.4318 0.9525)
			(end -0.4318 -0.9525)
			(stroke
				(width 0)
				(type default)
			)
			(fill no)
			(layer "B.CrtYd")
		)
		(fp_rect
			(start 0.4318 0.9525)
			(end -0.4318 -0.9525)
			(stroke
				(width 0)
				(type default)
			)
			(fill no)
			(layer "B.Fab")
		)
		(pad "1" smd custom
			(at 0 -0.4445 180)
			(size 0.1524 0.1524)
			(layers "B.Cu" "B.Mask" "B.Paste")
			(net "MB1_CM_SENSE_P")
			(options
				(clearance outline)
				(anchor circle)
			)
			(primitives
				(gr_poly
					(pts
						(arc
							(start 0.3048 0.2032)
							(mid 0.275042 0.275042)
							(end 0.2032 0.3048)
						)
						(arc
							(start -0.2032 0.3048)
							(mid -0.275042 0.275042)
							(end -0.3048 0.2032)
						)
						(arc
							(start -0.3048 -0.2032)
							(mid -0.275042 -0.275042)
							(end -0.2032 -0.3048)
						)
						(arc
							(start 0.2032 -0.3048)
							(mid 0.275042 -0.275042)
							(end 0.3048 -0.2032)
						)
					)
					(width 0)
					(fill yes)
				)
			)
		)
		(pad "2" smd custom
			(at 0 0.4445 180)
			(size 0.1524 0.1524)
			(layers "B.Cu" "B.Mask" "B.Paste")
			(net "MB1_CM_SENSE_N")
			(options
				(clearance outline)
				(anchor circle)
			)
			(primitives
				(gr_poly
					(pts
						(arc
							(start 0.3048 0.2032)
							(mid 0.275042 0.275042)
							(end 0.2032 0.3048)
						)
						(arc
							(start -0.2032 0.3048)
							(mid -0.275042 0.275042)
							(end -0.3048 0.2032)
						)
						(arc
							(start -0.3048 -0.2032)
							(mid -0.275042 -0.275042)
							(end -0.2032 -0.3048)
						)
						(arc
							(start 0.2032 -0.3048)
							(mid 0.275042 -0.275042)
							(end 0.3048 -0.2032)
						)
					)
					(width 0)
					(fill yes)
				)
			)
		)
	)
	(footprint ""
		(layer "B.Cu")
		(at 471.885518 -209.33029 -90)
		(property "Reference" "C662"
			(at 0 0 90)
			(layer "B.SilkS")
			(hide yes)
			(effects
				(font
					(size 1.27 1.27)
				)
				(justify mirror)
			)
		)
		(property "Value" "SC10U16V5KX-7-GP-U"
			(at 0.0762 -6.1214 270)
			(unlocked yes)
			(layer "B.Fab")
			(hide yes)
			(effects
				(font
					(size 1.016 1.016)
					(thickness 0.1524)
				)
				(justify mirror)
			)
		)
		(property "Device Type" "C805H58"
			(at 0.0762 -8.1534 270)
			(unlocked yes)
			(layer "B.Fab")
			(hide yes)
			(effects
				(font
					(size 1.016 1.016)
					(thickness 0.1524)
				)
				(justify mirror)
			)
		)
		(duplicate_pad_numbers_are_jumpers no)
		(fp_line
			(start -0.635 0)
			(end 0.635 0)
			(stroke
				(width 0.508)
				(type default)
			)
			(layer "B.SilkS")
		)
		(fp_rect
			(start 0.9652 1.778)
			(end -0.9652 -1.778)
			(stroke
				(width 0)
				(type default)
			)
			(fill no)
			(layer "B.CrtYd")
		)
		(fp_poly
			(pts
				(xy 0.9652 -1.778) (xy -0.9652 -1.778) (xy -0.9652 1.778) (xy 0.9652 1.778)
			)
			(stroke
				(width 0)
				(type default)
			)
			(fill no)
			(layer "B.Fab")
		)
		(pad "1" smd rect
			(at 0 -0.9652 90)
			(size 1.397 1.143)
			(layers "B.Cu" "B.Mask" "B.Paste")
			(net "P5V_A_4")
		)
		(pad "2" smd rect
			(at 0 0.9652 90)
			(size 1.397 1.143)
			(layers "B.Cu" "B.Mask" "B.Paste")
			(net "GND")
		)
	)
	(footprint ""
		(layer "B.Cu")
		(at 42.749978 -164.200078 180)
		(property "Reference" "NUT3"
			(at 0 0 0)
			(layer "B.SilkS")
			(hide yes)
			(effects
				(font
					(size 1.27 1.27)
				)
				(justify mirror)
			)
		)
		(property "Value" "STF256R168H278-GP"
			(at 4.826 0.0508 180)
			(unlocked yes)
			(layer "B.Fab")
			(hide yes)
			(effects
				(font
					(size 1.016 1.016)
					(thickness 0.1524)
				)
				(justify mirror)
			)
		)
		(property "Device Type" "STF256R168H278"
			(at 4.826 -1.4732 180)
			(unlocked yes)
			(layer "B.Fab")
			(hide yes)
			(effects
				(font
					(size 1.016 1.016)
					(thickness 0.1524)
				)
				(justify mirror)
			)
		)
		(duplicate_pad_numbers_are_jumpers no)
		(fp_circle
			(center 0 0)
			(end -3.6068 0)
			(stroke
				(width 0.3048)
				(type default)
			)
			(fill no)
			(layer "B.SilkS")
		)
		(fp_poly
			(pts
				(arc
					(start -2.5019 0)
					(mid 2.5019 0)
					(end -2.5019 0)
				)
			)
			(stroke
				(width 0)
				(type default)
			)
			(fill no)
			(layer "B.CrtYd")
		)
		(fp_poly
			(pts
				(arc
					(start -3.7592 0.00635)
					(mid 3.759205 0)
					(end -3.7592 -0.00635)
				)
				(arc
					(start -2.5019 -0.00635)
					(mid 2.501908 0)
					(end -2.5019 0.00635)
				)
			)
			(stroke
				(width 0)
				(type default)
			)
			(fill no)
			(layer "B.CrtYd")
		)
		(fp_poly
			(pts
				(arc
					(start -3.7592 0)
					(mid 3.7592 0)
					(end -3.7592 0)
				)
			)
			(stroke
				(width 0)
				(type default)
			)
			(fill no)
			(layer "F.CrtYd")
		)
		(fp_poly
			(pts
				(arc
					(start -3.7592 0)
					(mid 3.7592 0)
					(end -3.7592 0)
				)
			)
			(stroke
				(width 0)
				(type default)
			)
			(fill no)
			(layer "B.Fab")
		)
		(fp_poly
			(pts
				(arc
					(start -3.7592 0)
					(mid 3.7592 0)
					(end -3.7592 0)
				)
			)
			(stroke
				(width 0)
				(type default)
			)
			(fill no)
			(layer "F.Fab")
		)
		(pad "1" thru_hole circle
			(at 0 0)
			(size 6.5024 6.5024)
			(drill 4.2672)
			(layers "*.Cu" "*.Mask")
			(remove_unused_layers no)
			(net "Net_13")
			(clearance -0.6096)
			(padstack
				(mode front_inner_back)
				(layer "Inner"
					(shape circle)
					(size 4.6736 4.6736)
					(clearance 0.3048)
				)
				(layer "B.Cu"
					(shape circle)
					(size 6.5024 6.5024)
					(thermal_gap 0.3048)
					(clearance -0.6096)
				)
			)
		)
	)
	(footprint ""
		(layer "B.Cu")
		(at 478.231454 -239.216184 180)
		(property "Reference" "C655"
			(at 0 0 0)
			(layer "B.SilkS")
			(hide yes)
			(effects
				(font
					(size 1.27 1.27)
				)
				(justify mirror)
			)
		)
		(property "Value" "SC4D7U25V5KX-GP"
			(at 0.0762 -6.1214 180)
			(unlocked yes)
			(layer "B.Fab")
			(hide yes)
			(effects
				(font
					(size 1.016 1.016)
					(thickness 0.1524)
				)
				(justify mirror)
			)
		)
		(property "Device Type" "C805H54"
			(at 0.0762 -8.1534 180)
			(unlocked yes)
			(layer "B.Fab")
			(hide yes)
			(effects
				(font
					(size 1.016 1.016)
					(thickness 0.1524)
				)
				(justify mirror)
			)
		)
		(duplicate_pad_numbers_are_jumpers no)
		(fp_line
			(start -0.635 0)
			(end 0.635 0)
			(stroke
				(width 0.508)
				(type default)
			)
			(layer "B.SilkS")
		)
		(fp_rect
			(start 0.9652 1.778)
			(end -0.9652 -1.778)
			(stroke
				(width 0)
				(type default)
			)
			(fill no)
			(layer "B.CrtYd")
		)
		(fp_poly
			(pts
				(xy 0.9652 -1.778) (xy -0.9652 -1.778) (xy -0.9652 1.778) (xy 0.9652 1.778)
			)
			(stroke
				(width 0)
				(type default)
			)
			(fill no)
			(layer "B.Fab")
		)
		(pad "1" smd rect
			(at 0 -0.9652)
			(size 1.397 1.143)
			(layers "B.Cu" "B.Mask" "B.Paste")
			(net "P12V_A_VDD_U27")
		)
		(pad "2" smd rect
			(at 0 0.9652)
			(size 1.397 1.143)
			(layers "B.Cu" "B.Mask" "B.Paste")
			(net "GND")
		)
	)
	(footprint ""
		(layer "B.Cu")
		(at 217.6526 -123.4948)
		(property "Reference" "R639"
			(at 0 0 0)
			(layer "B.SilkS")
			(hide yes)
			(effects
				(font
					(size 1.27 1.27)
				)
				(justify mirror)
			)
		)
		(property "Value" "0R2J-2-GP"
			(at -0.064008 -3.993896 0)
			(unlocked yes)
			(layer "B.Fab")
			(hide yes)
			(effects
				(font
					(size 1.016 1.016)
					(thickness 0.1524)
				)
				(justify mirror)
			)
		)
		(property "Device Type" "R402H16"
			(at -0.064008 -5.517896 0)
			(unlocked yes)
			(layer "B.Fab")
			(hide yes)
			(effects
				(font
					(size 1.016 1.016)
					(thickness 0.1524)
				)
				(justify mirror)
			)
		)
		(duplicate_pad_numbers_are_jumpers no)
		(fp_line
			(start -0.508 -0.9398)
			(end 0.508 -0.9398)
			(stroke
				(width 0.1524)
				(type default)
			)
			(layer "B.SilkS")
		)
		(fp_line
			(start 0.508 -0.9398)
			(end 0.508 0.9398)
			(stroke
				(width 0.1524)
				(type default)
			)
			(layer "B.SilkS")
		)
		(fp_rect
			(start 0.508 0.9398)
			(end -0.508 -0.9398)
			(stroke
				(width 0)
				(type default)
			)
			(fill no)
			(layer "B.CrtYd")
		)
		(fp_rect
			(start 0.508 0.9398)
			(end -0.508 -0.9398)
			(stroke
				(width 0)
				(type default)
			)
			(fill no)
			(layer "B.Fab")
		)
		(pad "1" smd custom
			(at 0 -0.4445 180)
			(size 0.1397 0.1397)
			(layers "B.Cu" "B.Mask" "B.Paste")
			(net "I2C_BMC_A_COMP_A_SDA_R")
			(options
				(clearance outline)
				(anchor circle)
			)
			(primitives
				(gr_poly
					(pts
						(arc
							(start -0.1778 0.2794)
							(mid -0.249642 0.249642)
							(end -0.2794 0.1778)
						)
						(arc
							(start -0.2794 -0.1778)
							(mid -0.249642 -0.249642)
							(end -0.1778 -0.2794)
						)
						(arc
							(start 0.1778 -0.2794)
							(mid 0.249642 -0.249642)
							(end 0.2794 -0.1778)
						)
						(arc
							(start 0.2794 0.1778)
							(mid 0.249642 0.249642)
							(end 0.1778 0.2794)
						)
					)
					(width 0)
					(fill yes)
				)
			)
		)
		(pad "2" smd custom
			(at 0 0.4445 180)
			(size 0.1397 0.1397)
			(layers "B.Cu" "B.Mask" "B.Paste")
			(net "I2C_BMC_A_COMP_A_SDA_BUF")
			(options
				(clearance outline)
				(anchor circle)
			)
			(primitives
				(gr_poly
					(pts
						(arc
							(start -0.1778 0.2794)
							(mid -0.249642 0.249642)
							(end -0.2794 0.1778)
						)
						(arc
							(start -0.2794 -0.1778)
							(mid -0.249642 -0.249642)
							(end -0.1778 -0.2794)
						)
						(arc
							(start 0.1778 -0.2794)
							(mid 0.249642 -0.249642)
							(end 0.2794 -0.1778)
						)
						(arc
							(start 0.2794 0.1778)
							(mid 0.249642 0.249642)
							(end 0.1778 0.2794)
						)
					)
					(width 0)
					(fill yes)
				)
			)
		)
	)
	(footprint ""
		(layer "B.Cu")
		(at 23.257002 -250.88215 -90)
		(property "Reference" "C604"
			(at 0 0 90)
			(layer "B.SilkS")
			(hide yes)
			(effects
				(font
					(size 1.27 1.27)
				)
				(justify mirror)
			)
		)
		(property "Value" "SC4D7U25V5KX-GP"
			(at 0.0762 -6.1214 270)
			(unlocked yes)
			(layer "B.Fab")
			(hide yes)
			(effects
				(font
					(size 1.016 1.016)
					(thickness 0.1524)
				)
				(justify mirror)
			)
		)
		(property "Device Type" "C805H54"
			(at 0.0762 -8.1534 270)
			(unlocked yes)
			(layer "B.Fab")
			(hide yes)
			(effects
				(font
					(size 1.016 1.016)
					(thickness 0.1524)
				)
				(justify mirror)
			)
		)
		(duplicate_pad_numbers_are_jumpers no)
		(fp_line
			(start -0.635 0)
			(end 0.635 0)
			(stroke
				(width 0.508)
				(type default)
			)
			(layer "B.SilkS")
		)
		(fp_rect
			(start 0.9652 1.778)
			(end -0.9652 -1.778)
			(stroke
				(width 0)
				(type default)
			)
			(fill no)
			(layer "B.CrtYd")
		)
		(fp_poly
			(pts
				(xy 0.9652 -1.778) (xy -0.9652 -1.778) (xy -0.9652 1.778) (xy 0.9652 1.778)
			)
			(stroke
				(width 0)
				(type default)
			)
			(fill no)
			(layer "B.Fab")
		)
		(pad "1" smd rect
			(at 0 -0.9652 90)
			(size 1.397 1.143)
			(layers "B.Cu" "B.Mask" "B.Paste")
			(net "P12V_A_VDD_U20")
		)
		(pad "2" smd rect
			(at 0 0.9652 90)
			(size 1.397 1.143)
			(layers "B.Cu" "B.Mask" "B.Paste")
			(net "GND")
		)
	)
	(footprint ""
		(layer "B.Cu")
		(at 480.680522 -228.4095)
		(property "Reference" "R1265"
			(at 0 0 0)
			(layer "B.SilkS")
			(hide yes)
			(effects
				(font
					(size 1.27 1.27)
				)
				(justify mirror)
			)
		)
		(property "Value" "10KR2F-2-GP"
			(at -0.064008 -3.993896 0)
			(unlocked yes)
			(layer "B.Fab")
			(hide yes)
			(effects
				(font
					(size 1.016 1.016)
					(thickness 0.1524)
				)
				(justify mirror)
			)
		)
		(property "Device Type" "R402H16"
			(at -0.064008 -5.517896 0)
			(unlocked yes)
			(layer "B.Fab")
			(hide yes)
			(effects
				(font
					(size 1.016 1.016)
					(thickness 0.1524)
				)
				(justify mirror)
			)
		)
		(duplicate_pad_numbers_are_jumpers no)
		(fp_line
			(start -0.508 -0.9398)
			(end 0.508 -0.9398)
			(stroke
				(width 0.1524)
				(type default)
			)
			(layer "B.SilkS")
		)
		(fp_line
			(start 0.508 -0.9398)
			(end 0.508 0.9398)
			(stroke
				(width 0.1524)
				(type default)
			)
			(layer "B.SilkS")
		)
		(fp_rect
			(start 0.508 0.9398)
			(end -0.508 -0.9398)
			(stroke
				(width 0)
				(type default)
			)
			(fill no)
			(layer "B.CrtYd")
		)
		(fp_rect
			(start 0.508 0.9398)
			(end -0.508 -0.9398)
			(stroke
				(width 0)
				(type default)
			)
			(fill no)
			(layer "B.Fab")
		)
		(pad "1" smd custom
			(at 0 -0.4445 180)
			(size 0.1397 0.1397)
			(layers "B.Cu" "B.Mask" "B.Paste")
			(net "P5V_D_EN_R")
			(options
				(clearance outline)
				(anchor circle)
			)
			(primitives
				(gr_poly
					(pts
						(arc
							(start -0.1778 0.2794)
							(mid -0.249642 0.249642)
							(end -0.2794 0.1778)
						)
						(arc
							(start -0.2794 -0.1778)
							(mid -0.249642 -0.249642)
							(end -0.1778 -0.2794)
						)
						(arc
							(start 0.1778 -0.2794)
							(mid 0.249642 -0.249642)
							(end 0.2794 -0.1778)
						)
						(arc
							(start 0.2794 0.1778)
							(mid 0.249642 0.249642)
							(end 0.1778 0.2794)
						)
					)
					(width 0)
					(fill yes)
				)
			)
		)
		(pad "2" smd custom
			(at 0 0.4445 180)
			(size 0.1397 0.1397)
			(layers "B.Cu" "B.Mask" "B.Paste")
			(net "GND")
			(options
				(clearance outline)
				(anchor circle)
			)
			(primitives
				(gr_poly
					(pts
						(arc
							(start -0.1778 0.2794)
							(mid -0.249642 0.249642)
							(end -0.2794 0.1778)
						)
						(arc
							(start -0.2794 -0.1778)
							(mid -0.249642 -0.249642)
							(end -0.1778 -0.2794)
						)
						(arc
							(start 0.1778 -0.2794)
							(mid 0.249642 -0.249642)
							(end 0.2794 -0.1778)
						)
						(arc
							(start 0.2794 0.1778)
							(mid 0.249642 0.249642)
							(end 0.1778 0.2794)
						)
					)
					(width 0)
					(fill yes)
				)
			)
		)
	)
	(footprint ""
		(layer "B.Cu")
		(at 215.9254 -119.761)
		(property "Reference" "C2"
			(at 0 0 0)
			(layer "B.SilkS")
			(hide yes)
			(effects
				(font
					(size 1.27 1.27)
				)
				(justify mirror)
			)
		)
		(property "Value" "SCD1U16V2KX-3GP"
			(at -1.1811 -2.7051 0)
			(unlocked yes)
			(layer "B.Fab")
			(hide yes)
			(effects
				(font
					(size 1.016 1.016)
					(thickness 0.1524)
				)
				(justify mirror)
			)
		)
		(property "Device Type" "C402H22"
			(at -1.1811 -4.2291 0)
			(unlocked yes)
			(layer "B.Fab")
			(hide yes)
			(effects
				(font
					(size 1.016 1.016)
					(thickness 0.1524)
				)
				(justify mirror)
			)
		)
		(duplicate_pad_numbers_are_jumpers no)
		(fp_poly
			(pts
				(xy 0.4318 0.9525) (xy 0.4318 -0.9525) (xy -0.4318 -0.9525) (xy -0.4318 0.9525)
			)
			(stroke
				(width 0)
				(type default)
			)
			(fill no)
			(layer "B.CrtYd")
		)
		(fp_rect
			(start 0.4318 0.9525)
			(end -0.4318 -0.9525)
			(stroke
				(width 0)
				(type default)
			)
			(fill no)
			(layer "B.Fab")
		)
		(pad "1" smd custom
			(at 0 -0.4445 180)
			(size 0.1524 0.1524)
			(layers "B.Cu" "B.Mask" "B.Paste")
			(net "P3V3_STBY_A")
			(options
				(clearance outline)
				(anchor circle)
			)
			(primitives
				(gr_poly
					(pts
						(arc
							(start 0.3048 0.2032)
							(mid 0.275042 0.275042)
							(end 0.2032 0.3048)
						)
						(arc
							(start -0.2032 0.3048)
							(mid -0.275042 0.275042)
							(end -0.3048 0.2032)
						)
						(arc
							(start -0.3048 -0.2032)
							(mid -0.275042 -0.275042)
							(end -0.2032 -0.3048)
						)
						(arc
							(start 0.2032 -0.3048)
							(mid 0.275042 -0.275042)
							(end 0.3048 -0.2032)
						)
					)
					(width 0)
					(fill yes)
				)
			)
		)
		(pad "2" smd custom
			(at 0 0.4445 180)
			(size 0.1524 0.1524)
			(layers "B.Cu" "B.Mask" "B.Paste")
			(net "GND")
			(options
				(clearance outline)
				(anchor circle)
			)
			(primitives
				(gr_poly
					(pts
						(arc
							(start 0.3048 0.2032)
							(mid 0.275042 0.275042)
							(end 0.2032 0.3048)
						)
						(arc
							(start -0.2032 0.3048)
							(mid -0.275042 0.275042)
							(end -0.3048 0.2032)
						)
						(arc
							(start -0.3048 -0.2032)
							(mid -0.275042 -0.275042)
							(end -0.2032 -0.3048)
						)
						(arc
							(start 0.2032 -0.3048)
							(mid 0.275042 -0.275042)
							(end 0.3048 -0.2032)
						)
					)
					(width 0)
					(fill yes)
				)
			)
		)
	)
	(footprint ""
		(layer "B.Cu")
		(at 7.999984 -224.199958 180)
		(property "Reference" "NUT1"
			(at 0 0 0)
			(layer "B.SilkS")
			(hide yes)
			(effects
				(font
					(size 1.27 1.27)
				)
				(justify mirror)
			)
		)
		(property "Value" "STF256R168H278-GP"
			(at 4.826 0.0508 180)
			(unlocked yes)
			(layer "B.Fab")
			(hide yes)
			(effects
				(font
					(size 1.016 1.016)
					(thickness 0.1524)
				)
				(justify mirror)
			)
		)
		(property "Device Type" "STF256R168H278"
			(at 4.826 -1.4732 180)
			(unlocked yes)
			(layer "B.Fab")
			(hide yes)
			(effects
				(font
					(size 1.016 1.016)
					(thickness 0.1524)
				)
				(justify mirror)
			)
		)
		(duplicate_pad_numbers_are_jumpers no)
		(fp_circle
			(center 0 0)
			(end -3.6068 0)
			(stroke
				(width 0.3048)
				(type default)
			)
			(fill no)
			(layer "B.SilkS")
		)
		(fp_poly
			(pts
				(arc
					(start -2.5019 0)
					(mid 2.5019 0)
					(end -2.5019 0)
				)
			)
			(stroke
				(width 0)
				(type default)
			)
			(fill no)
			(layer "B.CrtYd")
		)
		(fp_poly
			(pts
				(arc
					(start -3.7592 0.00635)
					(mid 3.759205 0)
					(end -3.7592 -0.00635)
				)
				(arc
					(start -2.5019 -0.00635)
					(mid 2.501908 0)
					(end -2.5019 0.00635)
				)
			)
			(stroke
				(width 0)
				(type default)
			)
			(fill no)
			(layer "B.CrtYd")
		)
		(fp_poly
			(pts
				(arc
					(start -3.7592 0)
					(mid 3.7592 0)
					(end -3.7592 0)
				)
			)
			(stroke
				(width 0)
				(type default)
			)
			(fill no)
			(layer "F.CrtYd")
		)
		(fp_poly
			(pts
				(arc
					(start -3.7592 0)
					(mid 3.7592 0)
					(end -3.7592 0)
				)
			)
			(stroke
				(width 0)
				(type default)
			)
			(fill no)
			(layer "B.Fab")
		)
		(fp_poly
			(pts
				(arc
					(start -3.7592 0)
					(mid 3.7592 0)
					(end -3.7592 0)
				)
			)
			(stroke
				(width 0)
				(type default)
			)
			(fill no)
			(layer "F.Fab")
		)
		(pad "1" thru_hole circle
			(at 0 0)
			(size 6.5024 6.5024)
			(drill 4.2672)
			(layers "*.Cu" "*.Mask")
			(remove_unused_layers no)
			(net "Net_15")
			(clearance -0.6096)
			(padstack
				(mode front_inner_back)
				(layer "Inner"
					(shape circle)
					(size 4.6736 4.6736)
					(clearance 0.3048)
				)
				(layer "B.Cu"
					(shape circle)
					(size 6.5024 6.5024)
					(thermal_gap 0.3048)
					(clearance -0.6096)
				)
			)
		)
	)
)
